(kicad_pcb
	(version 20260206)
	(generator "pcbnew")
	(generator_version "10.0")
	(general
		(thickness 1.6)
		(legacy_teardrops no)
	)
	(paper "A4")
	(title_block
		(title "Bryce Canyon_R.DPB_16317-1_OCP.brd")
		(comment 1 "Bryce Canyon / footprints 1283-1289 of 2099")
	)
	(layers
		(0 "F.Cu" signal "TOP")
		(4 "In1.Cu" signal "L2GND")
		(6 "In2.Cu" signal "L3")
		(8 "In3.Cu" signal "L4VCC")
		(10 "In4.Cu" signal "L5VCC")
		(12 "In5.Cu" signal "L6")
		(14 "In6.Cu" signal "L7GND")
		(2 "B.Cu" signal "BOTTOM")
		(9 "F.Adhes" user "F.Adhesive")
		(11 "B.Adhes" user "B.Adhesive")
		(13 "F.Paste" user "Package Geometry/Pastemask Top")
		(15 "B.Paste" user "Package Geometry/Pastemask Bottom")
		(5 "F.SilkS" user "Ref Des/Silkscreen Top")
		(7 "B.SilkS" user "Ref Des/Silkscreen Bottom")
		(1 "F.Mask" user "Board Geometry/Soldermask Top")
		(3 "B.Mask" user "Board Geometry/Soldermask Bottom")
		(17 "Dwgs.User" user "User.Drawings")
		(19 "Cmts.User" user "User.Comments")
		(21 "Eco1.User" user "User.Eco1")
		(23 "Eco2.User" user "User.Eco2")
		(25 "Edge.Cuts" user "Board Geometry/Outline")
		(27 "Margin" user)
		(31 "F.CrtYd" user "Package Geometry/Place Bound Top")
		(29 "B.CrtYd" user "Package Geometry/Place Bound Bottom")
		(35 "F.Fab" user "Ref Des/Assembly Top")
		(33 "B.Fab" user "Ref Des/Assembly Bottom")
	)
	(footprint ""
		(layer "F.Cu")
		(at 36.035996 -370.078 90)
		(property "Reference" "R924"
			(at 0 0 90)
			(layer "F.SilkS")
			(hide yes)
			(effects
				(font
					(size 1.27 1.27)
				)
			)
		)
		(property "Value" "27KR3F-GP"
			(at -0.0254 -2.5146 90)
			(unlocked yes)
			(layer "F.Fab")
			(hide yes)
			(effects
				(font
					(size 1.016 1.016)
					(thickness 0.1524)
				)
			)
		)
		(property "Device Type" "R603H22"
			(at -0.0254 -4.0386 90)
			(unlocked yes)
			(layer "F.Fab")
			(hide yes)
			(effects
				(font
					(size 1.016 1.016)
					(thickness 0.1524)
				)
			)
		)
		(duplicate_pad_numbers_are_jumpers no)
		(fp_line
			(start 0.2032 0)
			(end 0.4826 0)
			(stroke
				(width 0.2032)
				(type default)
			)
			(layer "F.SilkS")
		)
		(fp_line
			(start -0.4826 0)
			(end -0.2032 0)
			(stroke
				(width 0.2032)
				(type default)
			)
			(layer "F.SilkS")
		)
		(fp_rect
			(start -0.5842 1.3335)
			(end 0.5842 -1.3335)
			(stroke
				(width 0)
				(type default)
			)
			(fill no)
			(layer "F.CrtYd")
		)
		(fp_rect
			(start -0.5842 1.3335)
			(end 0.5842 -1.3335)
			(stroke
				(width 0)
				(type default)
			)
			(fill no)
			(layer "F.Fab")
		)
		(pad "1" smd custom
			(at 0 -0.762 90)
			(size 0.2159 0.2159)
			(layers "F.Cu" "F.Mask" "F.Paste")
			(net "FANTACH_R0")
			(options
				(clearance outline)
				(anchor circle)
			)
			(primitives
				(gr_poly
					(pts
						(arc
							(start -0.3302 -0.4318)
							(mid -0.402042 -0.402042)
							(end -0.4318 -0.3302)
						)
						(arc
							(start -0.4318 0.3302)
							(mid -0.402042 0.402042)
							(end -0.3302 0.4318)
						)
						(arc
							(start 0.3302 0.4318)
							(mid 0.402042 0.402042)
							(end 0.4318 0.3302)
						)
						(arc
							(start 0.4318 -0.3302)
							(mid 0.402042 -0.402042)
							(end 0.3302 -0.4318)
						)
					)
					(width 0)
					(fill yes)
				)
			)
		)
		(pad "2" smd custom
			(at 0 0.762 90)
			(size 0.2159 0.2159)
			(layers "F.Cu" "F.Mask" "F.Paste")
			(net "FAN_0_TACH0")
			(options
				(clearance outline)
				(anchor circle)
			)
			(primitives
				(gr_poly
					(pts
						(arc
							(start -0.3302 -0.4318)
							(mid -0.402042 -0.402042)
							(end -0.4318 -0.3302)
						)
						(arc
							(start -0.4318 0.3302)
							(mid -0.402042 0.402042)
							(end -0.3302 0.4318)
						)
						(arc
							(start 0.3302 0.4318)
							(mid 0.402042 0.402042)
							(end 0.4318 0.3302)
						)
						(arc
							(start 0.4318 -0.3302)
							(mid 0.402042 -0.402042)
							(end 0.3302 -0.4318)
						)
					)
					(width 0)
					(fill yes)
				)
			)
		)
	)
	(footprint ""
		(layer "F.Cu")
		(at 395.224 -243.586)
		(property "Reference" "R295"
			(at 0 0 0)
			(layer "F.SilkS")
			(hide yes)
			(effects
				(font
					(size 1.27 1.27)
				)
			)
		)
		(property "Value" "4K7R2F-GP"
			(at 0.064008 -3.993896 0)
			(unlocked yes)
			(layer "F.Fab")
			(hide yes)
			(effects
				(font
					(size 1.016 1.016)
					(thickness 0.1524)
				)
			)
		)
		(property "Device Type" "R402H16"
			(at 0.064008 -5.517896 0)
			(unlocked yes)
			(layer "F.Fab")
			(hide yes)
			(effects
				(font
					(size 1.016 1.016)
					(thickness 0.1524)
				)
			)
		)
		(duplicate_pad_numbers_are_jumpers no)
		(fp_line
			(start -0.508 -0.9398)
			(end -0.508 0.9398)
			(stroke
				(width 0.1524)
				(type default)
			)
			(layer "F.SilkS")
		)
		(fp_line
			(start 0.508 -0.9398)
			(end -0.508 -0.9398)
			(stroke
				(width 0.1524)
				(type default)
			)
			(layer "F.SilkS")
		)
		(fp_rect
			(start -0.508 0.9398)
			(end 0.508 -0.9398)
			(stroke
				(width 0)
				(type default)
			)
			(fill no)
			(layer "F.CrtYd")
		)
		(fp_rect
			(start -0.508 0.9398)
			(end 0.508 -0.9398)
			(stroke
				(width 0)
				(type default)
			)
			(fill no)
			(layer "F.Fab")
		)
		(pad "1" smd custom
			(at 0 -0.4445)
			(size 0.1397 0.1397)
			(layers "F.Cu" "F.Mask" "F.Paste")
			(net "SW_PWR_R_HDD8")
			(options
				(clearance outline)
				(anchor circle)
			)
			(primitives
				(gr_poly
					(pts
						(arc
							(start -0.1778 -0.2794)
							(mid -0.249642 -0.249642)
							(end -0.2794 -0.1778)
						)
						(arc
							(start -0.2794 0.1778)
							(mid -0.249642 0.249642)
							(end -0.1778 0.2794)
						)
						(arc
							(start 0.1778 0.2794)
							(mid 0.249642 0.249642)
							(end 0.2794 0.1778)
						)
						(arc
							(start 0.2794 -0.1778)
							(mid 0.249642 -0.249642)
							(end 0.1778 -0.2794)
						)
					)
					(width 0)
					(fill yes)
				)
			)
		)
		(pad "2" smd custom
			(at 0 0.4445)
			(size 0.1397 0.1397)
			(layers "F.Cu" "F.Mask" "F.Paste")
			(net "GND")
			(options
				(clearance outline)
				(anchor circle)
			)
			(primitives
				(gr_poly
					(pts
						(arc
							(start -0.1778 -0.2794)
							(mid -0.249642 -0.249642)
							(end -0.2794 -0.1778)
						)
						(arc
							(start -0.2794 0.1778)
							(mid -0.249642 0.249642)
							(end -0.1778 0.2794)
						)
						(arc
							(start 0.1778 0.2794)
							(mid 0.249642 0.249642)
							(end 0.2794 0.1778)
						)
						(arc
							(start 0.2794 -0.1778)
							(mid 0.249642 -0.249642)
							(end 0.1778 -0.2794)
						)
					)
					(width 0)
					(fill yes)
				)
			)
		)
	)
	(footprint ""
		(layer "F.Cu")
		(at 190.258954 -248.750074 -90)
		(property "Reference" "VIA12"
			(at 0 0 270)
			(layer "F.SilkS")
			(hide yes)
			(effects
				(font
					(size 1.27 1.27)
				)
			)
		)
		(property "Value" "100OHM-8L-2D36MM-L16-GP"
			(at -3.4036 -0.4572 270)
			(unlocked yes)
			(layer "F.Fab")
			(hide yes)
			(effects
				(font
					(size 1.016 1.016)
					(thickness 0.1524)
				)
			)
		)
		(property "Device Type" "VIA-PCIE-4P-427097"
			(at -3.4036 -1.9812 270)
			(unlocked yes)
			(layer "F.Fab")
			(hide yes)
			(effects
				(font
					(size 1.016 1.016)
					(thickness 0.1524)
				)
			)
		)
		(duplicate_pad_numbers_are_jumpers no)
		(fp_rect
			(start -2.1336 0.4826)
			(end 2.1336 -0.4826)
			(stroke
				(width 0)
				(type default)
			)
			(fill no)
			(layer "F.CrtYd")
		)
		(fp_rect
			(start -2.1336 0.4826)
			(end 2.1336 -0.4826)
			(stroke
				(width 0)
				(type default)
			)
			(fill no)
			(layer "F.Fab")
		)
		(pad "1" thru_hole circle
			(at -1.651 0 270)
			(size 0.508 0.508)
			(drill 0.254)
			(layers "*.Cu" "*.Mask")
			(remove_unused_layers no)
			(net "GND")
			(clearance 0.2286)
			(thermal_gap 0.2286)
		)
		(pad "2" thru_hole circle
			(at -0.635 0 270)
			(size 0.508 0.508)
			(drill 0.254)
			(layers "*.Cu" "*.Mask")
			(remove_unused_layers no)
			(net "PHY_DRV_B_TO_SCC_B_5_DP")
			(clearance 0.2286)
			(thermal_gap 0.2286)
		)
		(pad "3" thru_hole circle
			(at 0.635 0 270)
			(size 0.508 0.508)
			(drill 0.254)
			(layers "*.Cu" "*.Mask")
			(remove_unused_layers no)
			(net "PHY_DRV_B_TO_SCC_B_5_DN")
			(clearance 0.2286)
			(thermal_gap 0.2286)
		)
		(pad "4" thru_hole circle
			(at 1.651 0 270)
			(size 0.508 0.508)
			(drill 0.254)
			(layers "*.Cu" "*.Mask")
			(remove_unused_layers no)
			(net "GND")
			(clearance 0.2286)
			(thermal_gap 0.2286)
		)
	)
	(footprint ""
		(layer "F.Cu")
		(at 469.9 -145.796)
		(property "Reference" "Q114"
			(at 0 0 0)
			(layer "F.SilkS")
			(hide yes)
			(effects
				(font
					(size 1.27 1.27)
				)
			)
		)
		(property "Value" "AO4407AL-GP"
			(at -3.707384 -1.5367 0)
			(unlocked yes)
			(layer "F.Fab")
			(hide yes)
			(effects
				(font
					(size 1.016 1.016)
					(thickness 0.1524)
				)
			)
		)
		(property "Device Type" "SOIC8H69"
			(at -3.707384 -3.0607 0)
			(unlocked yes)
			(layer "F.Fab")
			(hide yes)
			(effects
				(font
					(size 1.016 1.016)
					(thickness 0.1524)
				)
			)
		)
		(duplicate_pad_numbers_are_jumpers no)
		(fp_line
			(start -2.7432 -1.4224)
			(end -2.7432 1.4224)
			(stroke
				(width 0.1524)
				(type default)
			)
			(layer "F.SilkS")
		)
		(fp_line
			(start -2.7432 1.4224)
			(end -2.6416 1.4224)
			(stroke
				(width 0.1524)
				(type default)
			)
			(layer "F.SilkS")
		)
		(fp_line
			(start -2.7432 1.4224)
			(end 2.1336 1.4224)
			(stroke
				(width 0.1524)
				(type default)
			)
			(layer "F.SilkS")
		)
		(fp_line
			(start -2.7178 -0.508)
			(end -2.1844 -0.0508)
			(stroke
				(width 0.1524)
				(type default)
			)
			(layer "F.SilkS")
		)
		(fp_line
			(start -2.6289 3.4417)
			(end -2.6289 1.4732)
			(stroke
				(width 0.381)
				(type default)
			)
			(layer "F.SilkS")
		)
		(fp_line
			(start -2.1844 -0.0508)
			(end -2.7178 0.508)
			(stroke
				(width 0.1524)
				(type default)
			)
			(layer "F.SilkS")
		)
		(fp_line
			(start 2.1336 -1.4224)
			(end -2.7432 -1.4224)
			(stroke
				(width 0.1524)
				(type default)
			)
			(layer "F.SilkS")
		)
		(fp_line
			(start 2.1336 1.4224)
			(end 2.1336 -1.4224)
			(stroke
				(width 0.1524)
				(type default)
			)
			(layer "F.SilkS")
		)
		(fp_poly
			(pts
				(xy -2.2098 -1.4224) (xy -2.2098 1.4224) (xy 2.2098 1.4224) (xy 2.2098 -1.4224)
			)
			(stroke
				(width 0)
				(type default)
			)
			(fill yes)
			(layer "F.SilkS")
		)
		(fp_rect
			(start -2.450084 2.999994)
			(end 2.450084 -2.999994)
			(stroke
				(width 0)
				(type default)
			)
			(fill no)
			(layer "F.CrtYd")
		)
		(fp_poly
			(pts
				(xy -2.8194 3.6322) (xy -2.8194 -3.6322) (xy 2.8194 -3.6322) (xy 2.8194 1.18364) (xy 2.450084 1.18364)
				(xy 2.450084 -2.999994) (xy -2.450084 -2.999994) (xy -2.450084 2.999994) (xy 2.450084 2.999994)
				(xy 2.450084 1.18618) (xy 2.8194 1.18618) (xy 2.8194 3.6322)
			)
			(stroke
				(width 0)
				(type default)
			)
			(fill no)
			(layer "F.CrtYd")
		)
		(fp_rect
			(start -2.8194 3.6322)
			(end 2.8194 -3.6322)
			(stroke
				(width 0)
				(type default)
			)
			(fill no)
			(layer "F.Fab")
		)
		(pad "1" smd rect
			(at -1.905 2.54)
			(size 0.635 1.651)
			(layers "F.Cu" "F.Mask" "F.Paste")
			(net "P12V_B")
		)
		(pad "2" smd rect
			(at -0.635 2.54)
			(size 0.635 1.651)
			(layers "F.Cu" "F.Mask" "F.Paste")
			(net "P12V_B")
		)
		(pad "3" smd rect
			(at 0.635 2.54)
			(size 0.635 1.651)
			(layers "F.Cu" "F.Mask" "F.Paste")
			(net "P12V_B")
		)
		(pad "4" smd rect
			(at 1.905 2.54)
			(size 0.635 1.651)
			(layers "F.Cu" "F.Mask" "F.Paste")
			(net "SW_HDD_N23")
		)
		(pad "5" smd rect
			(at 1.905 -2.54)
			(size 0.635 1.651)
			(layers "F.Cu" "F.Mask" "F.Paste")
			(net "P12V_HDD23")
		)
		(pad "6" smd rect
			(at 0.635 -2.54)
			(size 0.635 1.651)
			(layers "F.Cu" "F.Mask" "F.Paste")
			(net "P12V_HDD23")
		)
		(pad "7" smd rect
			(at -0.635 -2.54)
			(size 0.635 1.651)
			(layers "F.Cu" "F.Mask" "F.Paste")
			(net "P12V_HDD23")
		)
		(pad "8" smd rect
			(at -1.905 -2.54)
			(size 0.635 1.651)
			(layers "F.Cu" "F.Mask" "F.Paste")
			(net "P12V_HDD23")
		)
	)
	(footprint ""
		(layer "F.Cu")
		(at 426.1866 -19.558 90)
		(property "Reference" "R836"
			(at 0 0 90)
			(layer "F.SilkS")
			(hide yes)
			(effects
				(font
					(size 1.27 1.27)
				)
			)
		)
		(property "Value" "4K7R2J-2-GP"
			(at 0.064008 -3.993896 90)
			(unlocked yes)
			(layer "F.Fab")
			(hide yes)
			(effects
				(font
					(size 1.016 1.016)
					(thickness 0.1524)
				)
			)
		)
		(property "Device Type" "R402H16"
			(at 0.064008 -5.517896 90)
			(unlocked yes)
			(layer "F.Fab")
			(hide yes)
			(effects
				(font
					(size 1.016 1.016)
					(thickness 0.1524)
				)
			)
		)
		(duplicate_pad_numbers_are_jumpers no)
		(fp_line
			(start 0.508 -0.9398)
			(end -0.508 -0.9398)
			(stroke
				(width 0.1524)
				(type default)
			)
			(layer "F.SilkS")
		)
		(fp_line
			(start -0.508 -0.9398)
			(end -0.508 0.9398)
			(stroke
				(width 0.1524)
				(type default)
			)
			(layer "F.SilkS")
		)
		(fp_rect
			(start -0.508 0.9398)
			(end 0.508 -0.9398)
			(stroke
				(width 0)
				(type default)
			)
			(fill no)
			(layer "F.CrtYd")
		)
		(fp_rect
			(start -0.508 0.9398)
			(end 0.508 -0.9398)
			(stroke
				(width 0)
				(type default)
			)
			(fill no)
			(layer "F.Fab")
		)
		(pad "1" smd custom
			(at 0 -0.4445 90)
			(size 0.1397 0.1397)
			(layers "F.Cu" "F.Mask" "F.Paste")
			(net "P12V_B")
			(options
				(clearance outline)
				(anchor circle)
			)
			(primitives
				(gr_poly
					(pts
						(arc
							(start -0.1778 -0.2794)
							(mid -0.249642 -0.249642)
							(end -0.2794 -0.1778)
						)
						(arc
							(start -0.2794 0.1778)
							(mid -0.249642 0.249642)
							(end -0.1778 0.2794)
						)
						(arc
							(start 0.1778 0.2794)
							(mid 0.249642 0.249642)
							(end 0.2794 0.1778)
						)
						(arc
							(start 0.2794 -0.1778)
							(mid 0.249642 -0.249642)
							(end 0.1778 -0.2794)
						)
					)
					(width 0)
					(fill yes)
				)
			)
		)
		(pad "2" smd custom
			(at 0 0.4445 90)
			(size 0.1397 0.1397)
			(layers "F.Cu" "F.Mask" "F.Paste")
			(net "SW_HDD_P33")
			(options
				(clearance outline)
				(anchor circle)
			)
			(primitives
				(gr_poly
					(pts
						(arc
							(start -0.1778 -0.2794)
							(mid -0.249642 -0.249642)
							(end -0.2794 -0.1778)
						)
						(arc
							(start -0.2794 0.1778)
							(mid -0.249642 0.249642)
							(end -0.1778 0.2794)
						)
						(arc
							(start 0.1778 0.2794)
							(mid 0.249642 0.249642)
							(end 0.2794 0.1778)
						)
						(arc
							(start 0.2794 -0.1778)
							(mid 0.249642 -0.249642)
							(end 0.1778 -0.2794)
						)
					)
					(width 0)
					(fill yes)
				)
			)
		)
	)
	(footprint ""
		(layer "F.Cu")
		(at 331.0382 -17.5006 90)
		(property "Reference" "R767"
			(at 0 0 90)
			(layer "F.SilkS")
			(hide yes)
			(effects
				(font
					(size 1.27 1.27)
				)
			)
		)
		(property "Value" "4K7R2J-2-GP"
			(at 0.064008 -3.993896 90)
			(unlocked yes)
			(layer "F.Fab")
			(hide yes)
			(effects
				(font
					(size 1.016 1.016)
					(thickness 0.1524)
				)
			)
		)
		(property "Device Type" "R402H16"
			(at 0.064008 -5.517896 90)
			(unlocked yes)
			(layer "F.Fab")
			(hide yes)
			(effects
				(font
					(size 1.016 1.016)
					(thickness 0.1524)
				)
			)
		)
		(duplicate_pad_numbers_are_jumpers no)
		(fp_line
			(start 0.508 -0.9398)
			(end -0.508 -0.9398)
			(stroke
				(width 0.1524)
				(type default)
			)
			(layer "F.SilkS")
		)
		(fp_line
			(start -0.508 -0.9398)
			(end -0.508 0.9398)
			(stroke
				(width 0.1524)
				(type default)
			)
			(layer "F.SilkS")
		)
		(fp_rect
			(start -0.508 0.9398)
			(end 0.508 -0.9398)
			(stroke
				(width 0)
				(type default)
			)
			(fill no)
			(layer "F.CrtYd")
		)
		(fp_rect
			(start -0.508 0.9398)
			(end 0.508 -0.9398)
			(stroke
				(width 0)
				(type default)
			)
			(fill no)
			(layer "F.Fab")
		)
		(pad "1" smd custom
			(at 0 -0.4445 90)
			(size 0.1397 0.1397)
			(layers "F.Cu" "F.Mask" "F.Paste")
			(net "P12V_B")
			(options
				(clearance outline)
				(anchor circle)
			)
			(primitives
				(gr_poly
					(pts
						(arc
							(start -0.1778 -0.2794)
							(mid -0.249642 -0.249642)
							(end -0.2794 -0.1778)
						)
						(arc
							(start -0.2794 0.1778)
							(mid -0.249642 0.249642)
							(end -0.1778 0.2794)
						)
						(arc
							(start 0.1778 0.2794)
							(mid 0.249642 0.249642)
							(end 0.2794 0.1778)
						)
						(arc
							(start 0.2794 -0.1778)
							(mid 0.249642 -0.249642)
							(end 0.1778 -0.2794)
						)
					)
					(width 0)
					(fill yes)
				)
			)
		)
		(pad "2" smd custom
			(at 0 0.4445 90)
			(size 0.1397 0.1397)
			(layers "F.Cu" "F.Mask" "F.Paste")
			(net "SW_HDD_P30")
			(options
				(clearance outline)
				(anchor circle)
			)
			(primitives
				(gr_poly
					(pts
						(arc
							(start -0.1778 -0.2794)
							(mid -0.249642 -0.249642)
							(end -0.2794 -0.1778)
						)
						(arc
							(start -0.2794 0.1778)
							(mid -0.249642 0.249642)
							(end -0.1778 0.2794)
						)
						(arc
							(start 0.1778 0.2794)
							(mid 0.249642 0.249642)
							(end 0.2794 0.1778)
						)
						(arc
							(start 0.2794 -0.1778)
							(mid 0.249642 -0.249642)
							(end 0.1778 -0.2794)
						)
					)
					(width 0)
					(fill yes)
				)
			)
		)
	)
	(footprint ""
		(layer "F.Cu")
		(at 185.478928 -371.606826)
		(property "Reference" "R1302"
			(at 0 0 0)
			(layer "F.SilkS")
			(hide yes)
			(effects
				(font
					(size 1.27 1.27)
				)
			)
		)
		(property "Value" "4K7R2F-GP"
			(at 0.064008 -3.993896 0)
			(unlocked yes)
			(layer "F.Fab")
			(hide yes)
			(effects
				(font
					(size 1.016 1.016)
					(thickness 0.1524)
				)
			)
		)
		(property "Device Type" "R402H16"
			(at 0.064008 -5.517896 0)
			(unlocked yes)
			(layer "F.Fab")
			(hide yes)
			(effects
				(font
					(size 1.016 1.016)
					(thickness 0.1524)
				)
			)
		)
		(duplicate_pad_numbers_are_jumpers no)
		(fp_line
			(start -0.508 -0.9398)
			(end -0.508 0.9398)
			(stroke
				(width 0.1524)
				(type default)
			)
			(layer "F.SilkS")
		)
		(fp_line
			(start 0.508 -0.9398)
			(end -0.508 -0.9398)
			(stroke
				(width 0.1524)
				(type default)
			)
			(layer "F.SilkS")
		)
		(fp_rect
			(start -0.508 0.9398)
			(end 0.508 -0.9398)
			(stroke
				(width 0)
				(type default)
			)
			(fill no)
			(layer "F.CrtYd")
		)
		(fp_rect
			(start -0.508 0.9398)
			(end 0.508 -0.9398)
			(stroke
				(width 0)
				(type default)
			)
			(fill no)
			(layer "F.Fab")
		)
		(pad "1" smd custom
			(at 0 -0.4445)
			(size 0.1397 0.1397)
			(layers "F.Cu" "F.Mask" "F.Paste")
			(net "FAN_BLUE_LED1")
			(options
				(clearance outline)
				(anchor circle)
			)
			(primitives
				(gr_poly
					(pts
						(arc
							(start -0.1778 -0.2794)
							(mid -0.249642 -0.249642)
							(end -0.2794 -0.1778)
						)
						(arc
							(start -0.2794 0.1778)
							(mid -0.249642 0.249642)
							(end -0.1778 0.2794)
						)
						(arc
							(start 0.1778 0.2794)
							(mid 0.249642 0.249642)
							(end 0.2794 0.1778)
						)
						(arc
							(start 0.2794 -0.1778)
							(mid 0.249642 -0.249642)
							(end 0.1778 -0.2794)
						)
					)
					(width 0)
					(fill yes)
				)
			)
		)
		(pad "2" smd custom
			(at 0 0.4445)
			(size 0.1397 0.1397)
			(layers "F.Cu" "F.Mask" "F.Paste")
			(net "FAN_LED1_D")
			(options
				(clearance outline)
				(anchor circle)
			)
			(primitives
				(gr_poly
					(pts
						(arc
							(start -0.1778 -0.2794)
							(mid -0.249642 -0.249642)
							(end -0.2794 -0.1778)
						)
						(arc
							(start -0.2794 0.1778)
							(mid -0.249642 0.249642)
							(end -0.1778 0.2794)
						)
						(arc
							(start 0.1778 0.2794)
							(mid 0.249642 0.249642)
							(end 0.2794 0.1778)
						)
						(arc
							(start 0.2794 -0.1778)
							(mid 0.249642 -0.249642)
							(end 0.1778 -0.2794)
						)
					)
					(width 0)
					(fill yes)
				)
			)
		)
	)
)
